# T6G (Grand Teton) — schematic netlist excerpt (pin names and nets, part order shuffled) for the footprints in the layout excerpt that follows; sources: Cadence DE-HDL packaged netlist, KiCad conversion of 04192023_DAF0TMB3IC0_F0TG_MB_C_brd_V02_OCP.brd

PU6503  ISL99390FRZTR5935  ISL99390FRZ-TR5935 IC  pkg QFN21_6X5XB  page 363
  VOS  = P0V9_RETIMER_CPU0_VOS1
  AGND  = GND
  VCC  = P0V9_RETIMER_CPU0_VCC1
  PVCC  = P0V9_RETIMER_CPU0_PVCC
  PGND1  = GND
  GL1  = NC_PV09_RETIMER_CPU0_GL1_1
  PGND2  = GND
  SW  = SW_P0V9_RETIMER_CPU0_SW1
  VIN1  = SW_P12V_AUX_P0V9_RETIMER_CPU0_FLT
  VIN2  = SW_P12V_AUX_P0V9_RETIMER_CPU0_FLT
  DNC  = NC_PV09_RETIMER_CPU0_DNC1
  PHASE  = SW_P0V9_RETIMER_CPU0_PH1
  BOOT  = SW_P0V9_RETIMER_CPU0_BOOT1
  PWM  = P0V9_RETIMER_CPU0_PWM1
  EN  = P0V9_RETIMER_CPU0_VCC1
  TOUT_FLT  = P0V9_RETIMER_CPU0_TEMP0
  LSET  = P0V9_RETIMER_CPU0_LSET1
  IOUT  = P0V9_RETIMER_CPU0_IMON1
  REFIN  = PV09_RETIMER_CPU0_VCCS
  PGND3  = GND
  GL2  = NC_PV09_RETIMER_CPU0_GL2_1

(kicad_pcb
	(version 20260206)
	(generator "pcbnew")
	(generator_version "10.0")
	(general
		(thickness 1.6)
		(legacy_teardrops no)
	)
	(paper "A4")
	(title_block
		(title "04192023_DAF0TMB3IC0_F0TG_MB_C_brd_V02_OCP.brd")
		(comment 1 "Grand Teton / footprint 4514 of 8354 (PU6503), pads 1-21 of 21")
	)
	(layers
		(0 "F.Cu" signal "TOP")
		(4 "In1.Cu" signal "GND")
		(6 "In2.Cu" signal "IN1")
		(8 "In3.Cu" signal "GND1")
		(10 "In4.Cu" signal "IN2")
		(12 "In5.Cu" signal "GND2")
		(14 "In6.Cu" signal "IN3")
		(16 "In7.Cu" signal "GND3")
		(18 "In8.Cu" signal "VCC")
		(20 "In9.Cu" signal "VCC1")
		(22 "In10.Cu" signal "GND4")
		(24 "In11.Cu" signal "IN4")
		(26 "In12.Cu" signal "GND5")
		(28 "In13.Cu" signal "IN5")
		(30 "In14.Cu" signal "GND6")
		(32 "In15.Cu" signal "IN6")
		(34 "In16.Cu" signal "GND7")
		(2 "B.Cu" signal "BOTTOM")
		(9 "F.Adhes" user "F.Adhesive")
		(11 "B.Adhes" user "B.Adhesive")
		(13 "F.Paste" user "Package Geometry/Pastemask Top")
		(15 "B.Paste" user "Package Geometry/Pastemask Bottom")
		(5 "F.SilkS" user "Ref Des/Silkscreen Top")
		(7 "B.SilkS" user "Ref Des/Silkscreen Bottom")
		(1 "F.Mask" user "Board Geometry/Soldermask Top")
		(3 "B.Mask" user "Board Geometry/Soldermask Bottom")
		(17 "Dwgs.User" user "User.Drawings")
		(19 "Cmts.User" user "User.Comments")
		(21 "Eco1.User" user "User.Eco1")
		(23 "Eco2.User" user "User.Eco2")
		(25 "Edge.Cuts" user "Board Geometry/Outline")
		(27 "Margin" user)
		(31 "F.CrtYd" user "Package Geometry/Place Bound Top")
		(29 "B.CrtYd" user "Package Geometry/Place Bound Bottom")
		(35 "F.Fab" user "Ref Des/Assembly Top")
		(33 "B.Fab" user "Ref Des/Assembly Bottom")
	)
	(footprint ""
		(layer "F.Cu")
		(at 445.131952 -397.245332)
		(property "Reference" "PU6503"
			(at -3.99415 -7.331456 0)
			(unlocked yes)
			(layer "F.SilkS")
			(effects
				(font
					(size 0.7874 0.5842)
					(thickness 0.1524)
				)
				(justify left)
			)
		)
		(property "Value" ""
			(at 0 0 0)
			(layer "F.Fab")
			(effects
				(font
					(size 1.27 1.27)
				)
			)
		)
		(duplicate_pad_numbers_are_jumpers no)
		(pad "1" smd rect
			(at -2.400046 -2.275078 90)
			(size 0.2286 0.6096)
			(layers "F.Cu" "F.Mask" "F.Paste")
			(net "P0V9_RETIMER_CPU0_VOS1")
		)
		(pad "2" smd rect
			(at -2.400046 -1.82499 90)
			(size 0.2286 0.6096)
			(layers "F.Cu" "F.Mask" "F.Paste")
			(net "GND")
		)
		(pad "3" smd rect
			(at -2.400046 -1.374902 90)
			(size 0.2286 0.6096)
			(layers "F.Cu" "F.Mask" "F.Paste")
			(net "P0V9_RETIMER_CPU0_VCC1")
		)
		(pad "4" smd rect
			(at -2.400046 -0.925068 90)
			(size 0.2286 0.6096)
			(layers "F.Cu" "F.Mask" "F.Paste")
			(net "P0V9_RETIMER_CPU0_PVCC")
		)
		(pad "5" smd rect
			(at -2.400046 -0.47498 90)
			(size 0.2286 0.6096)
			(layers "F.Cu" "F.Mask" "F.Paste")
			(net "GND")
		)
		(pad "6" smd rect
			(at -2.400046 -0.024892 90)
			(size 0.2286 0.6096)
			(layers "F.Cu" "F.Mask" "F.Paste")
			(net "NC_PV09_RETIMER_CPU0_GL1_1")
		)
		(pad "7_9-20_24" smd circle
			(at 0 1.150112 90)
			(size 0 0)
			(layers "F.Cu" "F.Mask" "F.Paste")
			(net "GND")
		)
		(pad "10_19" smd rect
			(at 0 2.899918 90)
			(size 0.6096 4.318)
			(layers "F.Cu" "F.Mask" "F.Paste")
			(net "SW_P0V9_RETIMER_CPU0_SW1")
		)
		(pad "25_29" smd rect
			(at 1.549908 -1.279906 270)
			(size 2.0574 2.3114)
			(layers "F.Cu" "F.Mask" "F.Paste")
			(net "SW_P12V_AUX_P0V9_RETIMER_CPU0_FLT")
		)
		(pad "30" smd rect
			(at 2.05994 -2.899918)
			(size 0.2286 0.6096)
			(layers "F.Cu" "F.Mask" "F.Paste")
			(net "SW_P12V_AUX_P0V9_RETIMER_CPU0_FLT")
		)
		(pad "31" smd rect
			(at 1.610106 -2.899918)
			(size 0.2286 0.6096)
			(layers "F.Cu" "F.Mask" "F.Paste")
			(net "NC_PV09_RETIMER_CPU0_DNC1")
		)
		(pad "32" smd rect
			(at 1.160018 -2.899918)
			(size 0.2286 0.6096)
			(layers "F.Cu" "F.Mask" "F.Paste")
			(net "SW_P0V9_RETIMER_CPU0_PH1")
		)
		(pad "33" smd rect
			(at 0.70993 -2.899918)
			(size 0.2286 0.6096)
			(layers "F.Cu" "F.Mask" "F.Paste")
			(net "SW_P0V9_RETIMER_CPU0_BOOT1")
		)
		(pad "34" smd rect
			(at 0.260096 -2.899918)
			(size 0.2286 0.6096)
			(layers "F.Cu" "F.Mask" "F.Paste")
			(net "P0V9_RETIMER_CPU0_PWM1")
		)
		(pad "35" smd rect
			(at -0.189992 -2.899918)
			(size 0.2286 0.6096)
			(layers "F.Cu" "F.Mask" "F.Paste")
			(net "P0V9_RETIMER_CPU0_VCC1")
		)
		(pad "36" smd rect
			(at -0.64008 -2.899918)
			(size 0.2286 0.6096)
			(layers "F.Cu" "F.Mask" "F.Paste")
			(net "P0V9_RETIMER_CPU0_TEMP0")
		)
		(pad "37" smd rect
			(at -1.089914 -2.899918)
			(size 0.2286 0.6096)
			(layers "F.Cu" "F.Mask" "F.Paste")
			(net "P0V9_RETIMER_CPU0_LSET1")
		)
		(pad "38" smd rect
			(at -1.540002 -2.899918)
			(size 0.2286 0.6096)
			(layers "F.Cu" "F.Mask" "F.Paste")
			(net "P0V9_RETIMER_CPU0_IMON1")
		)
		(pad "39" smd rect
			(at -1.99009 -2.899918)
			(size 0.2286 0.6096)
			(layers "F.Cu" "F.Mask" "F.Paste")
			(net "PV09_RETIMER_CPU0_VCCS")
		)
		(pad "40" smd rect
			(at -0.87503 -1.27508)
			(size 1.7526 1.9558)
			(layers "F.Cu" "F.Mask" "F.Paste")
			(net "GND")
		)
		(pad "41" smd rect
			(at -1.525016 0.249936 270)
			(size 0.3048 0.4572)
			(layers "F.Cu" "F.Mask" "F.Paste")
			(net "NC_PV09_RETIMER_CPU0_GL2_1")
		)
	)
)
